(kicad_pcb
	(version 20260206)
	(generator "pcbnew")
	(generator_version "10.0")
	(general
		(thickness 1.6)
		(legacy_teardrops no)
	)
	(paper "A4")
	(title_block
		(title "03242023_DA0F0TMBIJ0_F0T_Motherboard_J_brd_V01_OCP.brd")
		(comment 1 "Grand Teton / footprint 2414 of 6105 (J37), pads 110-175 of 175")
	)
	(layers
		(0 "F.Cu" signal "TOP")
		(4 "In1.Cu" signal "GND")
		(6 "In2.Cu" signal "IN1")
		(8 "In3.Cu" signal "GND1")
		(10 "In4.Cu" signal "IN2")
		(12 "In5.Cu" signal "GND2")
		(14 "In6.Cu" signal "IN3")
		(16 "In7.Cu" signal "GND3")
		(18 "In8.Cu" signal "VCC")
		(20 "In9.Cu" signal "VCC1")
		(22 "In10.Cu" signal "GND4")
		(24 "In11.Cu" signal "IN4")
		(26 "In12.Cu" signal "GND5")
		(28 "In13.Cu" signal "IN5")
		(30 "In14.Cu" signal "GND6")
		(32 "In15.Cu" signal "IN6")
		(34 "In16.Cu" signal "GND7")
		(2 "B.Cu" signal "BOTTOM")
		(9 "F.Adhes" user "F.Adhesive")
		(11 "B.Adhes" user "B.Adhesive")
		(13 "F.Paste" user "Package Geometry/Pastemask Top")
		(15 "B.Paste" user "Package Geometry/Pastemask Bottom")
		(5 "F.SilkS" user "Ref Des/Silkscreen Top")
		(7 "B.SilkS" user "Ref Des/Silkscreen Bottom")
		(1 "F.Mask" user "Board Geometry/Soldermask Top")
		(3 "B.Mask" user "Board Geometry/Soldermask Bottom")
		(17 "Dwgs.User" user "User.Drawings")
		(19 "Cmts.User" user "User.Comments")
		(21 "Eco1.User" user "User.Eco1")
		(23 "Eco2.User" user "User.Eco2")
		(25 "Edge.Cuts" user "Board Geometry/Outline")
		(27 "Margin" user)
		(31 "F.CrtYd" user "Package Geometry/Place Bound Top")
		(29 "B.CrtYd" user "Package Geometry/Place Bound Bottom")
		(35 "F.Fab" user "Ref Des/Assembly Top")
		(33 "B.Fab" user "Ref Des/Assembly Bottom")
	)
	(footprint ""
		(layer "F.Cu")
		(at 421.901874 -5.569966 -90)
		(property "Reference" "J37"
			(at -16.985996 31.63951 0)
			(unlocked yes)
			(layer "F.SilkS")
			(effects
				(font
					(size 0.7874 0.5842)
					(thickness 0.1524)
				)
				(justify left)
			)
		)
		(property "Value" ""
			(at 0 0 270)
			(layer "F.Fab")
			(effects
				(font
					(size 1.27 1.27)
				)
			)
		)
		(duplicate_pad_numbers_are_jumpers no)
		(pad "B38" smd rect
			(at -5.700014 7.14502 180)
			(size 0.381 1.4478)
			(layers "F.Cu" "F.Mask" "F.Paste")
			(net "GND")
		)
		(pad "B39" smd rect
			(at -5.700014 7.744968 180)
			(size 0.381 1.4478)
			(layers "F.Cu" "F.Mask" "F.Paste")
			(net "P5E_CPU0_PE1_TX_C_DN<7>")
		)
		(pad "B40" smd rect
			(at -5.700014 8.344916 180)
			(size 0.381 1.4478)
			(layers "F.Cu" "F.Mask" "F.Paste")
			(net "P5E_CPU0_PE1_TX_C_DP<7>")
		)
		(pad "B41" smd rect
			(at -5.700014 8.945118 180)
			(size 0.381 1.4478)
			(layers "F.Cu" "F.Mask" "F.Paste")
			(net "GND")
		)
		(pad "B42" smd rect
			(at -5.700014 9.545066 180)
			(size 0.381 1.4478)
			(layers "F.Cu" "F.Mask" "F.Paste")
			(net "OCP_SFF_PRSNT0_R_N")
		)
		(pad "B43" smd rect
			(at -5.700014 14.454886 180)
			(size 0.381 1.4478)
			(layers "F.Cu" "F.Mask" "F.Paste")
			(net "GND")
		)
		(pad "B44" smd rect
			(at -5.700014 15.055088 180)
			(size 0.381 1.4478)
			(layers "F.Cu" "F.Mask" "F.Paste")
			(net "P5E_CPU0_PE1_TX_C_DP<8>")
		)
		(pad "B45" smd rect
			(at -5.700014 15.655036 180)
			(size 0.381 1.4478)
			(layers "F.Cu" "F.Mask" "F.Paste")
			(net "P5E_CPU0_PE1_TX_C_DN<8>")
		)
		(pad "B46" smd rect
			(at -5.700014 16.254984 180)
			(size 0.381 1.4478)
			(layers "F.Cu" "F.Mask" "F.Paste")
			(net "GND")
		)
		(pad "B47" smd rect
			(at -5.700014 16.854932 180)
			(size 0.381 1.4478)
			(layers "F.Cu" "F.Mask" "F.Paste")
			(net "P5E_CPU0_PE1_TX_C_DN<9>")
		)
		(pad "B48" smd rect
			(at -5.700014 17.45488 180)
			(size 0.381 1.4478)
			(layers "F.Cu" "F.Mask" "F.Paste")
			(net "P5E_CPU0_PE1_TX_C_DP<9>")
		)
		(pad "B49" smd rect
			(at -5.700014 18.055082 180)
			(size 0.381 1.4478)
			(layers "F.Cu" "F.Mask" "F.Paste")
			(net "GND")
		)
		(pad "B50" smd rect
			(at -5.700014 18.65503 180)
			(size 0.381 1.4478)
			(layers "F.Cu" "F.Mask" "F.Paste")
			(net "P5E_CPU0_PE1_TX_C_DP<10>")
		)
		(pad "B51" smd rect
			(at -5.700014 19.254978 180)
			(size 0.381 1.4478)
			(layers "F.Cu" "F.Mask" "F.Paste")
			(net "P5E_CPU0_PE1_TX_C_DN<10>")
		)
		(pad "B52" smd rect
			(at -5.700014 19.854926 180)
			(size 0.381 1.4478)
			(layers "F.Cu" "F.Mask" "F.Paste")
			(net "GND")
		)
		(pad "B53" smd rect
			(at -5.700014 20.455128 180)
			(size 0.381 1.4478)
			(layers "F.Cu" "F.Mask" "F.Paste")
			(net "P5E_CPU0_PE1_TX_C_DN<11>")
		)
		(pad "B54" smd rect
			(at -5.700014 21.055076 180)
			(size 0.381 1.4478)
			(layers "F.Cu" "F.Mask" "F.Paste")
			(net "P5E_CPU0_PE1_TX_C_DP<11>")
		)
		(pad "B55" smd rect
			(at -5.700014 21.655024 180)
			(size 0.381 1.4478)
			(layers "F.Cu" "F.Mask" "F.Paste")
			(net "GND")
		)
		(pad "B56" smd rect
			(at -5.700014 22.254972 180)
			(size 0.381 1.4478)
			(layers "F.Cu" "F.Mask" "F.Paste")
			(net "P5E_CPU0_PE1_TX_C_DP<12>")
		)
		(pad "B57" smd rect
			(at -5.700014 22.85492 180)
			(size 0.381 1.4478)
			(layers "F.Cu" "F.Mask" "F.Paste")
			(net "P5E_CPU0_PE1_TX_C_DN<12>")
		)
		(pad "B58" smd rect
			(at -5.700014 23.455122 180)
			(size 0.381 1.4478)
			(layers "F.Cu" "F.Mask" "F.Paste")
			(net "GND")
		)
		(pad "B59" smd rect
			(at -5.700014 24.05507 180)
			(size 0.381 1.4478)
			(layers "F.Cu" "F.Mask" "F.Paste")
			(net "P5E_CPU0_PE1_TX_C_DN<13>")
		)
		(pad "B60" smd rect
			(at -5.700014 24.655018 180)
			(size 0.381 1.4478)
			(layers "F.Cu" "F.Mask" "F.Paste")
			(net "P5E_CPU0_PE1_TX_C_DP<13>")
		)
		(pad "B61" smd rect
			(at -5.700014 25.254966 180)
			(size 0.381 1.4478)
			(layers "F.Cu" "F.Mask" "F.Paste")
			(net "GND")
		)
		(pad "B62" smd rect
			(at -5.700014 25.854914 180)
			(size 0.381 1.4478)
			(layers "F.Cu" "F.Mask" "F.Paste")
			(net "P5E_CPU0_PE1_TX_C_DP<14>")
		)
		(pad "B63" smd rect
			(at -5.700014 26.455116 180)
			(size 0.381 1.4478)
			(layers "F.Cu" "F.Mask" "F.Paste")
			(net "P5E_CPU0_PE1_TX_C_DN<14>")
		)
		(pad "B64" smd rect
			(at -5.700014 27.055064 180)
			(size 0.381 1.4478)
			(layers "F.Cu" "F.Mask" "F.Paste")
			(net "GND")
		)
		(pad "B65" smd rect
			(at -5.700014 27.655012 180)
			(size 0.381 1.4478)
			(layers "F.Cu" "F.Mask" "F.Paste")
			(net "P5E_CPU0_PE1_TX_C_DN<15>")
		)
		(pad "B66" smd rect
			(at -5.700014 28.25496 180)
			(size 0.381 1.4478)
			(layers "F.Cu" "F.Mask" "F.Paste")
			(net "P5E_CPU0_PE1_TX_C_DP<15>")
		)
		(pad "B67" smd rect
			(at -5.700014 28.854908 180)
			(size 0.381 1.4478)
			(layers "F.Cu" "F.Mask" "F.Paste")
			(net "GND")
		)
		(pad "B68" smd rect
			(at -5.700014 29.45511 180)
			(size 0.381 1.4478)
			(layers "F.Cu" "F.Mask" "F.Paste")
			(net "TP_OCP_SFF_B68")
		)
		(pad "B69" smd rect
			(at -5.700014 30.055058 180)
			(size 0.381 1.4478)
			(layers "F.Cu" "F.Mask" "F.Paste")
			(net "TP_OCP_SFF_B69")
		)
		(pad "B70" smd rect
			(at -5.700014 30.655006 180)
			(size 0.381 1.4478)
			(layers "F.Cu" "F.Mask" "F.Paste")
			(net "OCP_SFF_PRSNT3_R_N")
		)
		(pad "G1" thru_hole circle
			(at 2.400046 -32.759904 180)
			(size 1.6256 1.6256)
			(drill 1.1176)
			(layers "*.Cu" "*.Mask")
			(remove_unused_layers no)
			(net "GND")
			(clearance 0)
		)
		(pad "G2" thru_hole circle
			(at 2.400046 -20.379944 180)
			(size 1.6256 1.6256)
			(drill 1.1176)
			(layers "*.Cu" "*.Mask")
			(remove_unused_layers no)
			(net "GND")
			(clearance 0)
		)
		(pad "G3" thru_hole circle
			(at 2.400046 0 180)
			(size 1.6256 1.6256)
			(drill 1.1176)
			(layers "*.Cu" "*.Mask")
			(remove_unused_layers no)
			(net "GND")
			(clearance 0)
		)
		(pad "G4" thru_hole circle
			(at 2.400046 12.5349 180)
			(size 1.6256 1.6256)
			(drill 1.1176)
			(layers "*.Cu" "*.Mask")
			(remove_unused_layers no)
			(net "GND")
			(clearance 0)
		)
		(pad "G5" thru_hole circle
			(at 2.400046 32.759904 180)
			(size 1.6256 1.6256)
			(drill 1.1176)
			(layers "*.Cu" "*.Mask")
			(remove_unused_layers no)
			(net "GND")
			(clearance 0)
		)
		(pad "OA1" smd rect
			(at -2.750058 -30.660086 180)
			(size 0.381 1.4478)
			(layers "F.Cu" "F.Mask" "F.Paste")
			(net "RST_PERST2_OCP_SFF_N")
		)
		(pad "OA2" smd rect
			(at -2.750058 -30.059884 180)
			(size 0.381 1.4478)
			(layers "F.Cu" "F.Mask" "F.Paste")
			(net "RST_PERST3_OCP_SFF_N")
		)
		(pad "OA3" smd rect
			(at -2.750058 -29.459936 180)
			(size 0.381 1.4478)
			(layers "F.Cu" "F.Mask" "F.Paste")
			(net "IRQ_LVC3_OCP_SFF_WAKE_N")
		)
		(pad "OA4" smd rect
			(at -2.750058 -28.859988 180)
			(size 0.381 1.4478)
			(layers "F.Cu" "F.Mask" "F.Paste")
			(net "OCP_SFF_ISO1_RBT_ARB_IN")
		)
		(pad "OA5" smd rect
			(at -2.750058 -28.26004 180)
			(size 0.381 1.4478)
			(layers "F.Cu" "F.Mask" "F.Paste")
			(net "OCP_SFF_ISO2_RBT_ARB_OUT")
		)
		(pad "OA6" smd rect
			(at -2.750058 -27.660092 180)
			(size 0.381 1.4478)
			(layers "F.Cu" "F.Mask" "F.Paste")
			(net "OCP_SFF_ID1")
		)
		(pad "OA7" smd rect
			(at -2.750058 -27.05989 180)
			(size 0.381 1.4478)
			(layers "F.Cu" "F.Mask" "F.Paste")
			(net "NCSI_OCP_SFF_TX_EN")
		)
		(pad "OA8" smd rect
			(at -2.750058 -26.459942 180)
			(size 0.381 1.4478)
			(layers "F.Cu" "F.Mask" "F.Paste")
			(net "NCSI_OCP_SFF_TXD1")
		)
		(pad "OA9" smd rect
			(at -2.750058 -25.859994 180)
			(size 0.381 1.4478)
			(layers "F.Cu" "F.Mask" "F.Paste")
			(net "NCSI_OCP_SFF_TXD0")
		)
		(pad "OA10" smd rect
			(at -2.750058 -25.260046 180)
			(size 0.381 1.4478)
			(layers "F.Cu" "F.Mask" "F.Paste")
			(net "GND")
		)
		(pad "OA11" smd rect
			(at -2.750058 -24.660098 180)
			(size 0.381 1.4478)
			(layers "F.Cu" "F.Mask" "F.Paste")
			(net "CLK_100M_OCP_SFF_3_DN")
		)
		(pad "OA12" smd rect
			(at -2.750058 -24.059896 180)
			(size 0.381 1.4478)
			(layers "F.Cu" "F.Mask" "F.Paste")
			(net "CLK_100M_OCP_SFF_3_DP")
		)
		(pad "OA13" smd rect
			(at -2.750058 -23.459948 180)
			(size 0.381 1.4478)
			(layers "F.Cu" "F.Mask" "F.Paste")
			(net "GND")
		)
		(pad "OA14" smd rect
			(at -2.750058 -22.86 180)
			(size 0.381 1.4478)
			(layers "F.Cu" "F.Mask" "F.Paste")
			(net "CLK_50M_NCSI_OCP_SFF_ISO")
		)
		(pad "OB1" smd rect
			(at -5.700014 -30.660086 180)
			(size 0.381 1.4478)
			(layers "F.Cu" "F.Mask" "F.Paste")
			(net "FM_OCP_SFF_PWR_GOOD")
		)
		(pad "OB2" smd rect
			(at -5.700014 -30.059884 180)
			(size 0.381 1.4478)
			(layers "F.Cu" "F.Mask" "F.Paste")
			(net "OCP_SFF_MAIN_PWR_EN_R")
		)
		(pad "OB3" smd rect
			(at -5.700014 -29.459936 180)
			(size 0.381 1.4478)
			(layers "F.Cu" "F.Mask" "F.Paste")
			(net "SGPIO_OCP_SFF_LD_N")
		)
		(pad "OB4" smd rect
			(at -5.700014 -28.859988 180)
			(size 0.381 1.4478)
			(layers "F.Cu" "F.Mask" "F.Paste")
			(net "SGPIO_OCP_SFF_DATAIN")
		)
		(pad "OB5" smd rect
			(at -5.700014 -28.26004 180)
			(size 0.381 1.4478)
			(layers "F.Cu" "F.Mask" "F.Paste")
			(net "SGPIO_OCP_SFF_DATAOUT")
		)
		(pad "OB6" smd rect
			(at -5.700014 -27.660092 180)
			(size 0.381 1.4478)
			(layers "F.Cu" "F.Mask" "F.Paste")
			(net "SGPIO_OCP_SFF_CLK")
		)
		(pad "OB7" smd rect
			(at -5.700014 -27.05989 180)
			(size 0.381 1.4478)
			(layers "F.Cu" "F.Mask" "F.Paste")
			(net "OCP_SFF_ID0")
		)
		(pad "OB8" smd rect
			(at -5.700014 -26.459942 180)
			(size 0.381 1.4478)
			(layers "F.Cu" "F.Mask" "F.Paste")
			(net "NCSI_OCP_SFF_RXD1")
		)
		(pad "OB9" smd rect
			(at -5.700014 -25.859994 180)
			(size 0.381 1.4478)
			(layers "F.Cu" "F.Mask" "F.Paste")
			(net "NCSI_OCP_SFF_RXD0")
		)
		(pad "OB10" smd rect
			(at -5.700014 -25.260046 180)
			(size 0.381 1.4478)
			(layers "F.Cu" "F.Mask" "F.Paste")
			(net "GND")
		)
		(pad "OB11" smd rect
			(at -5.700014 -24.660098 180)
			(size 0.381 1.4478)
			(layers "F.Cu" "F.Mask" "F.Paste")
			(net "CLK_100M_OCP_SFF_2_DN")
		)
		(pad "OB12" smd rect
			(at -5.700014 -24.059896 180)
			(size 0.381 1.4478)
			(layers "F.Cu" "F.Mask" "F.Paste")
			(net "CLK_100M_OCP_SFF_2_DP")
		)
		(pad "OB13" smd rect
			(at -5.700014 -23.459948 180)
			(size 0.381 1.4478)
			(layers "F.Cu" "F.Mask" "F.Paste")
			(net "GND")
		)
		(pad "OB14" smd rect
			(at -5.700014 -22.86 180)
			(size 0.381 1.4478)
			(layers "F.Cu" "F.Mask" "F.Paste")
			(net "NCSI_OCP_SFF_CRS_DV")
		)
	)
)
